FILE_TYPE = CONNECTIVITY;
{Allegro Design Entry HDL 17.4-2019 S026 (4007227) 1/17/2022}
"PAGE_NUMBER" = 331;
0"NC";
1"P3V3_AUX\g";
2"GND\g";
3"GND\g";
4"GND\g";
5"GND\g";
6"P3V3_AUX\g";
7"GND\g";
8"P3V3_AUX\g";
9"GND\g";
10"P3V3_AUX\g";
11"GND\g";
12"GND\g";
13"P3V3_AUX\g";
14"GND\g";
15"GND\g";
16"GND\g";
17"P3V3_AUX\g";
18"GND\g";
19"P3V3_AUX\g";
20"GND\g";
21"GND\g";
22"P3V3_AUX\g";
23"P3V3_AUX\g";
24"GND\g";
25"GND\g";
26"P3V3_AUX\g";
27"P3V3_AUX\g";
28"P3V3_AUX\g";
29"GND\g";
30"GND\g";
31"GND\g";
32"P3V3_AUX\g";
33"GND\g";
34"GND\g";
35"P3V3_AUX\g";
36"GPU_3V3IO_RSVD4_N";
37"GPU_3V3IO_RSVD1";
38"HGX_DETECT";
39"HGX_DETECT_N_ISO";
40"HGX_DETECT_N";
41"P3V3_AUX\g";
42"GPU_3V3IO_RSVD1_ISO";
43"GPU_3V3IO_RSVD3_ISO";
44"GPU_3V3IO_RSVD4_ISO";
45"SWB_HSC_EN_BUF_R";
46"SWB_HSC_EN_BUF";
47"NC_U316_2Y";
48"GPU_3V3IO_RSVD1_N";
49"GPU_3V3IO_RSVD4";
50"GPU_3V3IO_RSVD3";
51"GPU_3V3IO_RSVD3_N";
52"SWB_HSC_EN";
%"UNIVERSAL_POWER"
"1","(-1975,4075)","0","pure_quanta_power","I10";
;
HDL_POWER"P3V3_AUX"
CDS_LIB"pure_quanta_power";
"A"1;
%"UNIVERSAL_GND"
"1","(5175,4775)","0","pure_quanta_power","I100";
;
CDS_LIB"pure_quanta_power"
HDL_POWER"GND";
"A"2;
%"UNIVERSAL_GND"
"1","(4000,4000)","0","pure_quanta_power","I101";
;
CDS_LIB"pure_quanta_power"
HDL_POWER"GND";
"A"3;
%"UNIVERSAL_GND"
"1","(3300,4225)","0","pure_quanta_power","I102";
;
CDS_LIB"pure_quanta_power"
HDL_POWER"GND";
"A"4;
%"Q_RES"
"1","(-650,6050)","0","pure_quanta","I107";
;
LOCATION"R4569"
$SEC"1"
CDS_SEC"1"
MATERIAL"EMPTY"
WATTAGE"1/16W"
VALUE"0"
TOLERANCE"5%"
PACK_TYPE"0402LF"
CDS_LIB"pure_quanta"
PART_NUMBER"CS00002JB13";
"B"
$PN"2"42;
"A"
$PN"1"37;
%"Q_RES"
"1","(-425,3125)","0","pure_quanta","I108";
;
LOCATION"R4571"
$SEC"1"
CDS_SEC"1"
VALUE"0"
TOLERANCE"5%"
MATERIAL"EMPTY"
WATTAGE"1/16W"
PACK_TYPE"0402LF"
CDS_LIB"pure_quanta"
PART_NUMBER"CS00002JB13";
"B"
$PN"2"44;
"A"
$PN"1"49;
%"Q_RES"
"1","(-425,4575)","0","pure_quanta","I109";
;
LOCATION"R4570"
$SEC"1"
CDS_SEC"1"
VALUE"0"
TOLERANCE"5%"
MATERIAL"EMPTY"
PACK_TYPE"0402LF"
WATTAGE"1/16W"
CDS_LIB"pure_quanta"
PART_NUMBER"CS00002JB13";
"B"
$PN"2"43;
"A"
$PN"1"50;
%"UNIVERSAL_GND"
"1","(-1975,4450)","0","pure_quanta_power","I11";
;
CDS_LIB"pure_quanta_power"
HDL_POWER"GND";
"A"5;
%"Q_RES"
"2","(325,1250)","2","pure_quanta","I110";
;
LOCATION"R4546"
$SEC"1"
CDS_SEC"1"
VALUE"100K"
PACK_TYPE"0402LF"
MATERIAL"EMPTY"
WATTAGE"1/16W"
TOLERANCE"1%"
CDS_LIB"pure_quanta"
PART_NUMBER"CS41002FB09";
"A"
$PN"1"23;
"B"
$PN"2"39;
%"Q_CAP"
"1","(1100,775)","0","pure_quanta","I111";
;
LOCATION"C6"
$SEC"1"
CDS_SEC"1"
VALUE"0.1UF"
TOLERANCE"10%"
VOLTAGE"25V"
PACK_TYPE"0402"
MATERIAL"EMPTY"
CDS_LIB"pure_quanta"
PART_NUMBER"CH4104K1B00";
"B"
$PN"2"24;
"A"
$PN"1"39;
%"Q_RES"
"2","(-1975,4725)","0","pure_quanta","I13";
;
LOCATION"R4159"
$SEC"1"
CDS_SEC"1"
WATTAGE"1/16W"
TOLERANCE"1%"
MATERIAL"EMPTY"
PACK_TYPE"0402LF"
VALUE"100K"
CDS_LIB"pure_quanta"
PART_NUMBER"CS41002FB09";
"A"
$PN"1"37;
"B"
$PN"2"5;
%"Q_RES"
"2","(-2000,5200)","0","pure_quanta","I14";
;
LOCATION"R4158"
$SEC"1"
CDS_SEC"1"
TOLERANCE"1%"
MATERIAL"EMPTY"
VALUE"54.9K"
WATTAGE"1/16W"
PACK_TYPE"0402LF"
CDS_LIB"pure_quanta"
PART_NUMBER"CS35492FB03";
"A"
$PN"1"6;
"B"
$PN"2"37;
%"UNIVERSAL_POWER"
"1","(-2000,5450)","0","pure_quanta_power","I15";
;
HDL_POWER"P3V3_AUX"
CDS_LIB"pure_quanta_power";
"A"6;
%"UNIVERSAL_GND"
"1","(-825,1775)","0","pure_quanta_power","I16";
;
CDS_LIB"pure_quanta_power"
HDL_POWER"GND";
"A"7;
%"MOSFET_NCH_DUAL"
"1","(-875,2150)","0","pure_quanta","I17";
;
LOCATION"Q136"
$SEC"1"
CDS_SEC"1"
MATERIAL"IC"
VALUE"PJT138K"
PART_TYPE"SMLF"
CDS_LIB"pure_quanta"
NEEDS_NO_SIZE"TRUE"
CDS_LMAN_SYM_OUTLINE"-150,150,150,-150"
PART_NUMBER"BAM138K0003";
"D1"
$PN"6"36;
"G1"
$PN"2"49;
"S1"
$PN"1"7;
%"Q_RES"
"2","(-825,2750)","0","pure_quanta","I18";
;
LOCATION"R4165"
$SEC"1"
CDS_SEC"1"
TOLERANCE"5%"
VALUE"4.7K"
WATTAGE"1/16W"
MATERIAL"CHIP"
PACK_TYPE"0402LF"
CDS_LIB"pure_quanta"
PART_NUMBER"CS24702JB10";
"A"
$PN"1"8;
"B"
$PN"2"36;
%"UNIVERSAL_POWER"
"1","(-825,2975)","0","pure_quanta_power","I19";
;
HDL_POWER"P3V3_AUX"
CDS_LIB"pure_quanta_power";
"A"8;
%"Q_RES"
"2","(-1975,1900)","0","pure_quanta","I2";
;
LOCATION"R4161"
$SEC"1"
CDS_SEC"1"
MATERIAL"EMPTY"
PACK_TYPE"0402LF"
TOLERANCE"1%"
VALUE"100K"
WATTAGE"1/16W"
CDS_LIB"pure_quanta"
PART_NUMBER"CS41002FB09";
"A"
$PN"1"49;
"B"
$PN"2"12;
%"UNIVERSAL_GND"
"1","(-800,3225)","0","pure_quanta_power","I20";
;
CDS_LIB"pure_quanta_power"
HDL_POWER"GND";
"A"9;
%"MOSFET_NCH_DUAL"
"1","(-850,3600)","0","pure_quanta","I21";
;
LOCATION"Q137"
$SEC"1"
CDS_SEC"1"
VALUE"PJT138K"
MATERIAL"IC"
PART_TYPE"SMLF"
CDS_LIB"pure_quanta"
NEEDS_NO_SIZE"TRUE"
CDS_LMAN_SYM_OUTLINE"-150,150,150,-150"
PART_NUMBER"BAM138K0003";
"D1"
$PN"6"51;
"G1"
$PN"2"50;
"S1"
$PN"1"9;
%"MOSFET_NCH_DUAL"
"2","(275,2450)","0","pure_quanta","I22";
;
LOCATION"Q136"
$SEC"2"
CDS_SEC"2"
PART_TYPE"SMLF"
VALUE"PJT138K"
MATERIAL"IC"
CDS_LMAN_SYM_OUTLINE"-150,150,150,-150"
NEEDS_NO_SIZE"TRUE"
CDS_LIB"pure_quanta"
PART_NUMBER"BAM138K0003";
"S2"
$PN"4"15;
"G2"
$PN"5"36;
"D2"
$PN"3"44;
%"Q_RES"
"2","(-800,4200)","0","pure_quanta","I23";
;
LOCATION"R4166"
$SEC"1"
CDS_SEC"1"
TOLERANCE"5%"
PACK_TYPE"0402LF"
WATTAGE"1/16W"
VALUE"4.7K"
MATERIAL"CHIP"
CDS_LIB"pure_quanta"
PART_NUMBER"CS24702JB10";
"A"
$PN"1"10;
"B"
$PN"2"51;
%"UNIVERSAL_POWER"
"1","(-800,4425)","0","pure_quanta_power","I24";
;
HDL_POWER"P3V3_AUX"
CDS_LIB"pure_quanta_power";
"A"10;
%"MOSFET_NCH_DUAL"
"1","(-875,4975)","0","pure_quanta","I25";
;
LOCATION"Q135"
$SEC"1"
CDS_SEC"1"
MATERIAL"IC"
PART_TYPE"SMLF"
VALUE"PJT138K"
CDS_LIB"pure_quanta"
NEEDS_NO_SIZE"TRUE"
CDS_LMAN_SYM_OUTLINE"-150,150,150,-150"
PART_NUMBER"BAM138K0003";
"D1"
$PN"6"48;
"G1"
$PN"2"37;
"S1"
$PN"1"11;
%"UNIVERSAL_GND"
"1","(-825,4600)","0","pure_quanta_power","I26";
;
CDS_LIB"pure_quanta_power"
HDL_POWER"GND";
"A"11;
%"Q_RES"
"2","(-825,5575)","0","pure_quanta","I27";
;
LOCATION"R4164"
$SEC"1"
CDS_SEC"1"
TOLERANCE"5%"
VALUE"4.7K"
WATTAGE"1/16W"
MATERIAL"CHIP"
PACK_TYPE"0402LF"
CDS_LIB"pure_quanta"
PART_NUMBER"CS24702JB10";
"A"
$PN"1"13;
"B"
$PN"2"48;
%"MOSFET_NCH_DUAL"
"2","(300,3900)","0","pure_quanta","I28";
;
LOCATION"Q137"
$SEC"2"
CDS_SEC"2"
VALUE"PJT138K"
PART_TYPE"SMLF"
MATERIAL"IC"
CDS_LIB"pure_quanta"
NEEDS_NO_SIZE"TRUE"
CDS_LMAN_SYM_OUTLINE"-150,150,150,-150"
PART_NUMBER"BAM138K0003";
"S2"
$PN"4"18;
"G2"
$PN"5"51;
"D2"
$PN"3"43;
%"MOSFET_NCH_DUAL"
"2","(275,5275)","0","pure_quanta","I29";
;
LOCATION"Q135"
$SEC"2"
CDS_SEC"2"
VALUE"PJT138K"
PART_TYPE"SMLF"
MATERIAL"IC"
CDS_LIB"pure_quanta"
NEEDS_NO_SIZE"TRUE"
CDS_LMAN_SYM_OUTLINE"-150,150,150,-150"
PART_NUMBER"BAM138K0003";
"S2"
$PN"4"14;
"G2"
$PN"5"48;
"D2"
$PN"3"42;
%"UNIVERSAL_GND"
"1","(-1975,1625)","0","pure_quanta_power","I3";
;
CDS_LIB"pure_quanta_power"
HDL_POWER"GND";
"A"12;
%"UNIVERSAL_POWER"
"1","(-825,5800)","0","pure_quanta_power","I30";
;
HDL_POWER"P3V3_AUX"
CDS_LIB"pure_quanta_power";
"A"13;
%"UNIVERSAL_GND"
"1","(325,4900)","0","pure_quanta_power","I31";
;
CDS_LIB"pure_quanta_power"
HDL_POWER"GND";
"A"14;
%"UNIVERSAL_GND"
"1","(325,2075)","0","pure_quanta_power","I32";
;
CDS_LIB"pure_quanta_power"
HDL_POWER"GND";
"A"15;
%"Q_CAP"
"1","(1100,2400)","0","pure_quanta","I33";
;
LOCATION"C5"
$SEC"1"
CDS_SEC"1"
TOLERANCE"10%"
VOLTAGE"25V"
MATERIAL"X7R"
PACK_TYPE"0402"
VALUE"0.1UF"
CDS_LIB"pure_quanta"
PART_NUMBER"CH4104K1B00";
"B"
$PN"2"16;
"A"
$PN"1"44;
%"UNIVERSAL_GND"
"1","(1100,2200)","0","pure_quanta_power","I34";
;
CDS_LIB"pure_quanta_power"
HDL_POWER"GND";
"A"16;
%"Q_RES"
"2","(325,2875)","0","pure_quanta","I35";
;
LOCATION"R4168"
$SEC"1"
CDS_SEC"1"
TOLERANCE"1%"
VALUE"100K"
MATERIAL"CHIP"
WATTAGE"1/16W"
PACK_TYPE"0402LF"
CDS_LIB"pure_quanta"
PART_NUMBER"CS41002FB09";
"A"
$PN"1"17;
"B"
$PN"2"44;
%"UNIVERSAL_POWER"
"1","(325,3100)","0","pure_quanta_power","I36";
;
HDL_POWER"P3V3_AUX"
CDS_LIB"pure_quanta_power";
"A"17;
%"UNIVERSAL_GND"
"1","(350,3525)","0","pure_quanta_power","I37";
;
CDS_LIB"pure_quanta_power"
HDL_POWER"GND";
"A"18;
%"Q_RES"
"2","(350,4325)","0","pure_quanta","I39";
;
LOCATION"R4169"
$SEC"1"
CDS_SEC"1"
TOLERANCE"1%"
VALUE"100K"
PACK_TYPE"0402LF"
WATTAGE"1/16W"
MATERIAL"CHIP"
CDS_LIB"pure_quanta"
PART_NUMBER"CS41002FB09";
"A"
$PN"1"19;
"B"
$PN"2"43;
%"Q_RES"
"2","(-2000,2375)","0","pure_quanta","I4";
;
LOCATION"R4160"
$SEC"1"
CDS_SEC"1"
VALUE"54.9K"
TOLERANCE"1%"
WATTAGE"1/16W"
MATERIAL"EMPTY"
PACK_TYPE"0402LF"
CDS_LIB"pure_quanta"
PART_NUMBER"CS35492FB03";
"A"
$PN"1"28;
"B"
$PN"2"49;
%"UNIVERSAL_POWER"
"1","(350,4550)","0","pure_quanta_power","I40";
;
HDL_POWER"P3V3_AUX"
CDS_LIB"pure_quanta_power";
"A"19;
%"UNIVERSAL_GND"
"1","(1125,3650)","0","pure_quanta_power","I41";
;
CDS_LIB"pure_quanta_power"
HDL_POWER"GND";
"A"20;
%"Q_CAP"
"1","(1125,3850)","0","pure_quanta","I42";
;
LOCATION"C7"
$SEC"1"
CDS_SEC"1"
PACK_TYPE"0402"
MATERIAL"X7R"
TOLERANCE"10%"
VOLTAGE"25V"
VALUE"0.1UF"
CDS_LIB"pure_quanta"
PART_NUMBER"CH4104K1B00";
"B"
$PN"2"20;
"A"
$PN"1"43;
%"UNIVERSAL_GND"
"1","(1100,5025)","0","pure_quanta_power","I43";
;
CDS_LIB"pure_quanta_power"
HDL_POWER"GND";
"A"21;
%"Q_CAP"
"1","(1100,5225)","0","pure_quanta","I44";
;
LOCATION"C4"
$SEC"1"
CDS_SEC"1"
PACK_TYPE"0402"
MATERIAL"X7R"
TOLERANCE"10%"
VOLTAGE"25V"
VALUE"0.1UF"
CDS_LIB"pure_quanta"
PART_NUMBER"CH4104K1B00";
"B"
$PN"2"21;
"A"
$PN"1"42;
%"Q_RES"
"2","(325,5700)","0","pure_quanta","I47";
;
LOCATION"R4167"
$SEC"1"
CDS_SEC"1"
TOLERANCE"1%"
VALUE"100K"
MATERIAL"CHIP"
PACK_TYPE"0402LF"
WATTAGE"1/16W"
CDS_LIB"pure_quanta"
PART_NUMBER"CS41002FB09";
"A"
$PN"1"22;
"B"
$PN"2"42;
%"UNIVERSAL_POWER"
"1","(325,5925)","0","pure_quanta_power","I48";
;
HDL_POWER"P3V3_AUX"
CDS_LIB"pure_quanta_power";
"A"22;
%"UNIVERSAL_POWER"
"1","(325,1475)","0","pure_quanta_power","I49";
;
HDL_POWER"P3V3_AUX"
CDS_LIB"pure_quanta_power";
"A"23;
%"UNIVERSAL_GND"
"1","(1100,575)","0","pure_quanta_power","I53";
;
CDS_LIB"pure_quanta_power"
HDL_POWER"GND";
"A"24;
%"UNIVERSAL_GND"
"1","(325,450)","0","pure_quanta_power","I54";
;
CDS_LIB"pure_quanta_power"
HDL_POWER"GND";
"A"25;
%"MOSFET_NCH_DUAL"
"2","(275,825)","0","pure_quanta","I55";
;
LOCATION"Q148"
$SEC"2"
CDS_SEC"2"
MATERIAL"IC"
PART_TYPE"SMLF"
VALUE"PJT138K"
CDS_LIB"pure_quanta"
NEEDS_NO_SIZE"TRUE"
CDS_LMAN_SYM_OUTLINE"-150,150,150,-150"
PART_NUMBER"BAM138K0003";
"S2"
$PN"4"25;
"G2"
$PN"5"38;
"D2"
$PN"3"39;
%"UNIVERSAL_POWER"
"1","(-825,1350)","0","pure_quanta_power","I56";
;
HDL_POWER"P3V3_AUX"
CDS_LIB"pure_quanta_power";
"A"26;
%"Q_RES"
"2","(-825,1125)","0","pure_quanta","I57";
;
LOCATION"R4545"
$SEC"1"
CDS_SEC"1"
WATTAGE"1/16W"
TOLERANCE"5%"
VALUE"4.7K"
MATERIAL"CHIP"
PACK_TYPE"0402LF"
CDS_LIB"pure_quanta"
PART_NUMBER"CS24702JB10";
"A"
$PN"1"26;
"B"
$PN"2"38;
%"UNIVERSAL_POWER"
"1","(-2000,1000)","0","pure_quanta_power","I58";
;
HDL_POWER"P3V3_AUX"
CDS_LIB"pure_quanta_power";
"A"27;
%"UNIVERSAL_POWER"
"1","(-2000,2625)","0","pure_quanta_power","I6";
;
HDL_POWER"P3V3_AUX"
CDS_LIB"pure_quanta_power";
"A"28;
%"UNIVERSAL_GND"
"1","(-825,150)","0","pure_quanta_power","I60";
;
CDS_LIB"pure_quanta_power"
HDL_POWER"GND";
"A"29;
%"MOSFET_NCH_DUAL"
"1","(-875,525)","0","pure_quanta","I61";
;
LOCATION"Q148"
$SEC"1"
CDS_SEC"1"
PART_TYPE"SMLF"
MATERIAL"IC"
VALUE"PJT138K"
CDS_LIB"pure_quanta"
NEEDS_NO_SIZE"TRUE"
CDS_LMAN_SYM_OUTLINE"-150,150,150,-150"
PART_NUMBER"BAM138K0003";
"D1"
$PN"6"38;
"G1"
$PN"2"40;
"S1"
$PN"1"29;
%"Q_RES"
"2","(-1975,275)","0","pure_quanta","I62";
;
LOCATION"R4544"
$SEC"1"
CDS_SEC"1"
PACK_TYPE"0402LF"
VALUE"100K"
TOLERANCE"1%"
WATTAGE"1/16W"
MATERIAL"EMPTY"
CDS_LIB"pure_quanta"
PART_NUMBER"CS41002FB09";
"A"
$PN"1"40;
"B"
$PN"2"30;
%"UNIVERSAL_GND"
"1","(-1975,0)","0","pure_quanta_power","I63";
;
CDS_LIB"pure_quanta_power"
HDL_POWER"GND";
"A"30;
%"UNIVERSAL_GND"
"1","(-1950,3075)","0","pure_quanta_power","I7";
;
CDS_LIB"pure_quanta_power"
HDL_POWER"GND";
"A"31;
%"Q_RES"
"2","(-1950,3350)","0","pure_quanta","I8";
;
LOCATION"R4163"
$SEC"1"
CDS_SEC"1"
PACK_TYPE"0402LF"
WATTAGE"1/16W"
VALUE"100K"
TOLERANCE"1%"
MATERIAL"EMPTY"
CDS_LIB"pure_quanta"
PART_NUMBER"CS41002FB09";
"A"
$PN"1"50;
"B"
$PN"2"31;
%"Q_RES"
"2","(-2000,750)","0","pure_quanta","I85";
;
LOCATION"R4543"
$SEC"1"
CDS_SEC"1"
WATTAGE"1/16W"
MATERIAL"CHIP"
PACK_TYPE"0402LF"
VALUE"1K"
TOLERANCE"1%"
CDS_LIB"pure_quanta"
PART_NUMBER"CS21002FB06";
"A"
$PN"1"27;
"B"
$PN"2"40;
%"74LVC2G17GW"
"1","(3975,4600)","0","pure_quanta","I86";
;
LOCATION"U316"
SEC"1"
MATERIAL"IC"
PART_TYPE"SMLF"
VALUE"74LVC2G17GW"
SEC_TYPE""
CDS_LIB"pure_quanta"
CDS_LMAN_SYM_OUTLINE"-225,275,225,-275"
NEEDS_NO_SIZE"TRUE"
PART_NUMBER"AL2G0017005";
"B0"
$PN"6"45;
"A1"
$PN"3"4;
"A0"
$PN"1"52;
"GND"
$PN"2"3;
"B1"
$PN"4"47;
"VCC"
$PN"5"41;
%"Q_RES"
"2","(2400,5075)","0","pure_quanta","I87";
;
LOCATION"R4548"
$SEC"1"
CDS_SEC"1"
VALUE"100K"
WATTAGE"1/16W"
MATERIAL"CHIP"
PACK_TYPE"0402LF"
TOLERANCE"1%"
CDS_LIB"pure_quanta"
PART_NUMBER"CS41002FB09";
"A"
$PN"1"52;
"B"
$PN"2"33;
%"UNIVERSAL_POWER"
"1","(2375,5800)","0","pure_quanta_power","I88";
;
HDL_POWER"P3V3_AUX"
CDS_LIB"pure_quanta_power";
"A"32;
%"Q_RES"
"2","(2375,5550)","0","pure_quanta","I89";
;
LOCATION"R4547"
$SEC"1"
CDS_SEC"1"
PACK_TYPE"0402LF"
VALUE"100K"
TOLERANCE"1%"
WATTAGE"1/16W"
MATERIAL"EMPTY"
CDS_LIB"pure_quanta"
PART_NUMBER"CS41002FB09";
"A"
$PN"1"32;
"B"
$PN"2"52;
%"Q_RES"
"2","(-1975,3825)","0","pure_quanta","I9";
;
LOCATION"R4162"
$SEC"1"
CDS_SEC"1"
TOLERANCE"1%"
VALUE"54.9K"
WATTAGE"1/16W"
MATERIAL"EMPTY"
PACK_TYPE"0402LF"
CDS_LIB"pure_quanta"
PART_NUMBER"CS35492FB03";
"A"
$PN"1"1;
"B"
$PN"2"50;
%"UNIVERSAL_GND"
"1","(2400,4900)","0","pure_quanta_power","I90";
;
CDS_LIB"pure_quanta_power"
HDL_POWER"GND";
"A"33;
%"UNIVERSAL_GND"
"1","(4100,5225)","0","pure_quanta_power","I92";
;
CDS_LIB"pure_quanta_power"
HDL_POWER"GND";
"A"34;
%"Q_CAP"
"1","(4100,5425)","0","pure_quanta","I93";
;
LOCATION"C8"
$SEC"1"
CDS_SEC"1"
TOLERANCE"10%"
PACK_TYPE"0402"
MATERIAL"X7R"
VOLTAGE"25V"
VALUE"0.1UF"
CDS_LIB"pure_quanta"
PART_NUMBER"CH4104K1B00";
"B"
$PN"2"34;
"A"
$PN"1"41;
%"UNIVERSAL_POWER"
"1","(4100,5675)","0","pure_quanta_power","I94";
;
HDL_POWER"P3V3_AUX"
CDS_LIB"pure_quanta_power";
"A"41;
%"UNIVERSAL_POWER"
"1","(5125,5775)","0","pure_quanta_power","I96";
;
HDL_POWER"P3V3_AUX"
CDS_LIB"pure_quanta_power";
"A"35;
%"Q_RES"
"1","(5375,5275)","0","pure_quanta","I97";
;
LOCATION"R4550"
$SEC"1"
CDS_SEC"1"
PACK_TYPE"0402LF"
VALUE"49.9"
MATERIAL"CHIP"
CDS_LIB"pure_quanta"
WATTAGE"1/16W"
TOLERANCE"1%"
PART_NUMBER"CS04992FB07";
"B"
$PN"2"46;
"A"
$PN"1"45;
%"Q_RES"
"2","(5125,5525)","0","pure_quanta","I98";
;
LOCATION"R4549"
$SEC"1"
CDS_SEC"1"
MATERIAL"EMPTY"
WATTAGE"1/16W"
TOLERANCE"5%"
VALUE"4.7K"
PACK_TYPE"0402LF"
CDS_LIB"pure_quanta"
PART_NUMBER"CS24702JB10";
"A"
$PN"1"35;
"B"
$PN"2"45;
%"Q_RES"
"2","(5175,5000)","0","pure_quanta","I99";
;
LOCATION"R4555"
$SEC"1"
CDS_SEC"1"
WATTAGE"1/16W"
VALUE"4.7K"
TOLERANCE"5%"
PACK_TYPE"0402LF"
MATERIAL"EMPTY"
CDS_LIB"pure_quanta"
PART_NUMBER"CS24702JB10";
"A"
$PN"1"45;
"B"
$PN"2"2;
END.
